# BASEBOARD_FAB2 (Tioga Pass) — schematic netlist excerpt (pin names and nets, part order shuffled) for the footprints in the layout excerpt that follows; sources: Cadence DE-HDL packaged netlist, KiCad conversion of Wiwynn_Tioga_Pass_MB.brd

C7G41  CAP  0.22UF 16V 10% X7R  pkg 0402  page 216 : A = P5V_STBY ; B = GND
R1E13  RES  68.1K 1% EMPTY  pkg 0402  page 207 : A = VR_PVCCIN_CPU1_PH2_OCSET ; B = GND
L7B1  INDUCTOR  0.47UH 1% IND  pkg SM  page 232 : INA = VR_PVPP_DEF_PHASE ; INB = PVPP_DEF

(kicad_pcb
	(version 20260206)
	(generator "pcbnew")
	(generator_version "10.0")
	(general
		(thickness 1.6)
		(legacy_teardrops no)
	)
	(paper "A4")
	(title_block
		(title "Wiwynn_Tioga_Pass_MB.brd")
		(comment 1 "Tioga Pass / footprints 1696-1698 of 4770")
	)
	(layers
		(0 "F.Cu" signal "TOP")
		(4 "In1.Cu" signal "L2GND")
		(6 "In2.Cu" signal "L3")
		(8 "In3.Cu" signal "L4GND")
		(10 "In4.Cu" signal "L5")
		(12 "In5.Cu" signal "L6GND")
		(14 "In6.Cu" signal "L7VCC")
		(16 "In7.Cu" signal "L8VCC")
		(18 "In8.Cu" signal "L9GND")
		(20 "In9.Cu" signal "L10")
		(22 "In10.Cu" signal "L11GND")
		(24 "In11.Cu" signal "L12")
		(26 "In12.Cu" signal "L13GND")
		(2 "B.Cu" signal "BOTTOM")
		(9 "F.Adhes" user "F.Adhesive")
		(11 "B.Adhes" user "B.Adhesive")
		(13 "F.Paste" user "Package Geometry/Pastemask Top")
		(15 "B.Paste" user "Package Geometry/Pastemask Bottom")
		(5 "F.SilkS" user "Ref Des/Silkscreen Top")
		(7 "B.SilkS" user "Ref Des/Silkscreen Bottom")
		(1 "F.Mask" user "Board Geometry/Soldermask Top")
		(3 "B.Mask" user "Board Geometry/Soldermask Bottom")
		(17 "Dwgs.User" user "User.Drawings")
		(19 "Cmts.User" user "User.Comments")
		(21 "Eco1.User" user "User.Eco1")
		(23 "Eco2.User" user "User.Eco2")
		(25 "Edge.Cuts" user "Board Geometry/Outline")
		(27 "Margin" user)
		(31 "F.CrtYd" user "Package Geometry/Place Bound Top")
		(29 "B.CrtYd" user "Package Geometry/Place Bound Bottom")
		(35 "F.Fab" user "Ref Des/Assembly Top")
		(33 "B.Fab" user "Ref Des/Assembly Bottom")
	)
	(footprint ""
		(layer "F.Cu")
		(at 28.851352 -64.089788 -90)
		(property "Reference" "R1E13"
			(at 0 0 270)
			(layer "F.SilkS")
			(hide yes)
			(effects
				(font
					(size 1.27 1.27)
				)
			)
		)
		(property "Value" ""
			(at 0 0 270)
			(layer "F.Fab")
			(effects
				(font
					(size 1.27 1.27)
				)
			)
		)
		(duplicate_pad_numbers_are_jumpers no)
		(fp_poly
			(pts
				(xy -0.2794 -0.1016) (xy 0.2794 -0.1016) (xy 0.2794 0.9906) (xy -0.2794 0.9906)
			)
			(stroke
				(width 0)
				(type default)
			)
			(fill no)
			(layer "F.CrtYd")
		)
		(fp_line
			(start -0.2794 0.9906)
			(end 0.2794 0.9906)
			(stroke
				(width 0.1)
				(type default)
			)
			(layer "F.Fab")
		)
		(fp_line
			(start 0.2794 0.9906)
			(end 0.2794 -0.1016)
			(stroke
				(width 0.1)
				(type default)
			)
			(layer "F.Fab")
		)
		(fp_line
			(start -0.2794 -0.1016)
			(end -0.2794 0.9906)
			(stroke
				(width 0.1)
				(type default)
			)
			(layer "F.Fab")
		)
		(fp_line
			(start 0.2794 -0.1016)
			(end -0.2794 -0.1016)
			(stroke
				(width 0.1)
				(type default)
			)
			(layer "F.Fab")
		)
		(pad "1" smd rect
			(at 0 0 270)
			(size 0.508 0.508)
			(layers "F.Cu" "F.Mask" "F.Paste")
			(net "VR_PVCCIN_CPU1_PH2_OCSET")
		)
		(pad "2" smd rect
			(at 0 0.889 270)
			(size 0.508 0.508)
			(layers "F.Cu" "F.Mask" "F.Paste")
			(net "GND")
		)
		(zone
			(layer "F.Cu")
			(hatch none 0.5)
			(connect_pads
				(clearance 0)
			)
			(min_thickness 0.25)
			(keepout
				(tracks not_allowed)
				(vias allowed)
				(pads allowed)
				(copperpour not_allowed)
				(footprints allowed)
			)
			(placement
				(enabled no)
				(sheetname "")
			)
			(fill
				(thermal_gap 0.5)
				(thermal_bridge_width 0.5)
				(island_removal_mode 0)
			)
			(polygon
				(pts
					(xy 28.216352 -64.343788) (xy 28.216352 -63.835788) (xy 28.597352 -63.835788) (xy 28.597352 -64.343788)
				)
			)
		)
		(zone
			(layer "F.Cu")
			(hatch none 0.5)
			(connect_pads
				(clearance 0)
			)
			(min_thickness 0.25)
			(keepout
				(tracks allowed)
				(vias not_allowed)
				(pads allowed)
				(copperpour not_allowed)
				(footprints allowed)
			)
			(placement
				(enabled no)
				(sheetname "")
			)
			(fill
				(thermal_gap 0.5)
				(thermal_bridge_width 0.5)
				(island_removal_mode 0)
			)
			(polygon
				(pts
					(xy 28.597352 -64.343788) (xy 28.597352 -63.835788) (xy 28.216352 -63.835788) (xy 28.216352 -64.343788)
				)
			)
		)
	)
	(footprint ""
		(layer "F.Cu")
		(at 347.113606 -2.127504 -90)
		(property "Reference" "C7G41"
			(at 0 0 270)
			(layer "F.SilkS")
			(hide yes)
			(effects
				(font
					(size 1.27 1.27)
				)
			)
		)
		(property "Value" ""
			(at 0 0 270)
			(layer "F.Fab")
			(effects
				(font
					(size 1.27 1.27)
				)
			)
		)
		(duplicate_pad_numbers_are_jumpers no)
		(fp_rect
			(start -0.3048 -0.1016)
			(end 0.3048 0.9906)
			(stroke
				(width 0)
				(type default)
			)
			(fill no)
			(layer "F.CrtYd")
		)
		(fp_line
			(start -0.3048 0.9906)
			(end 0.3048 0.9906)
			(stroke
				(width 0.1)
				(type default)
			)
			(layer "F.Fab")
		)
		(fp_line
			(start 0.3048 0.9906)
			(end 0.3048 -0.1016)
			(stroke
				(width 0.1)
				(type default)
			)
			(layer "F.Fab")
		)
		(fp_line
			(start -0.3048 -0.1016)
			(end -0.3048 0.9906)
			(stroke
				(width 0.1)
				(type default)
			)
			(layer "F.Fab")
		)
		(fp_line
			(start 0.3048 -0.1016)
			(end -0.3048 -0.1016)
			(stroke
				(width 0.1)
				(type default)
			)
			(layer "F.Fab")
		)
		(pad "1" smd rect
			(at 0 0 270)
			(size 0.508 0.508)
			(layers "F.Cu" "F.Mask" "F.Paste")
			(net "P5V_STBY")
		)
		(pad "2" smd rect
			(at 0 0.889 270)
			(size 0.508 0.508)
			(layers "F.Cu" "F.Mask" "F.Paste")
			(net "GND")
		)
		(zone
			(layer "F.Cu")
			(hatch none 0.5)
			(connect_pads
				(clearance 0)
			)
			(min_thickness 0.25)
			(keepout
				(tracks allowed)
				(vias not_allowed)
				(pads allowed)
				(copperpour not_allowed)
				(footprints allowed)
			)
			(placement
				(enabled no)
				(sheetname "")
			)
			(fill
				(thermal_gap 0.5)
				(thermal_bridge_width 0.5)
				(island_removal_mode 0)
			)
			(polygon
				(pts
					(xy 346.859606 -2.381504) (xy 346.478606 -2.381504) (xy 346.478606 -1.873504) (xy 346.859606 -1.873504)
				)
			)
		)
		(zone
			(layer "F.Cu")
			(hatch none 0.5)
			(connect_pads
				(clearance 0)
			)
			(min_thickness 0.25)
			(keepout
				(tracks not_allowed)
				(vias allowed)
				(pads allowed)
				(copperpour not_allowed)
				(footprints allowed)
			)
			(placement
				(enabled no)
				(sheetname "")
			)
			(fill
				(thermal_gap 0.5)
				(thermal_bridge_width 0.5)
				(island_removal_mode 0)
			)
			(polygon
				(pts
					(xy 346.859606 -2.381504) (xy 346.478606 -2.381504) (xy 346.478606 -1.873504) (xy 346.859606 -1.873504)
				)
			)
		)
	)
	(footprint ""
		(layer "F.Cu")
		(at 337.7311 -134.493 -90)
		(property "Reference" "L7B1"
			(at 5.08 6.99643 90)
			(unlocked yes)
			(layer "F.SilkS")
			(effects
				(font
					(size 0.7874 0.5842)
					(thickness 0.1524)
				)
				(justify left)
			)
		)
		(property "Value" ""
			(at 0 0 270)
			(layer "F.Fab")
			(effects
				(font
					(size 1.27 1.27)
				)
			)
		)
		(duplicate_pad_numbers_are_jumpers no)
		(fp_line
			(start -3.4036 6.1341)
			(end -3.4036 -0.6731)
			(stroke
				(width 0.1524)
				(type default)
			)
			(layer "F.SilkS")
		)
		(fp_line
			(start -2.5654 6.1341)
			(end -3.4036 6.1341)
			(stroke
				(width 0.1524)
				(type default)
			)
			(layer "F.SilkS")
		)
		(fp_line
			(start 3.4036 6.1341)
			(end 2.5654 6.1341)
			(stroke
				(width 0.1524)
				(type default)
			)
			(layer "F.SilkS")
		)
		(fp_line
			(start -3.4036 -0.6731)
			(end -2.5654 -0.6731)
			(stroke
				(width 0.1524)
				(type default)
			)
			(layer "F.SilkS")
		)
		(fp_line
			(start 2.5654 -0.6731)
			(end 3.4036 -0.6731)
			(stroke
				(width 0.1524)
				(type default)
			)
			(layer "F.SilkS")
		)
		(fp_line
			(start 3.4036 -0.6731)
			(end 3.4036 6.1341)
			(stroke
				(width 0.1524)
				(type default)
			)
			(layer "F.SilkS")
		)
		(fp_poly
			(pts
				(xy -3.4036 -0.6731) (xy -3.4036 6.1341) (xy 3.4036 6.1341) (xy 3.4036 -0.6731)
			)
			(stroke
				(width 0)
				(type default)
			)
			(fill no)
			(layer "F.CrtYd")
		)
		(fp_line
			(start -3.4036 6.1341)
			(end -3.4036 -0.6731)
			(stroke
				(width 0.1)
				(type default)
			)
			(layer "F.Fab")
		)
		(fp_line
			(start 3.4036 6.1341)
			(end -3.4036 6.1341)
			(stroke
				(width 0.1)
				(type default)
			)
			(layer "F.Fab")
		)
		(fp_line
			(start -3.4036 -0.6731)
			(end 3.4036 -0.6731)
			(stroke
				(width 0.1)
				(type default)
			)
			(layer "F.Fab")
		)
		(fp_line
			(start 3.4036 -0.6731)
			(end 3.4036 6.1341)
			(stroke
				(width 0.1)
				(type default)
			)
			(layer "F.Fab")
		)
		(pad "1" smd rect
			(at 0 0 270)
			(size 3.556 3.175)
			(layers "F.Cu" "F.Mask" "F.Paste")
			(net "VR_PVPP_DEF_PHASE")
		)
		(pad "2" smd rect
			(at 0 5.461 270)
			(size 3.556 3.175)
			(layers "F.Cu" "F.Mask" "F.Paste")
			(net "PVPP_DEF")
		)
	)
)
